# T6G (Grand Teton) — schematic netlist excerpt (pin names and nets, part order shuffled) for the footprints in the layout excerpt that follows; sources: Cadence DE-HDL packaged netlist, KiCad conversion of 04192023_DAF0TMB3IC0_F0TG_MB_C_brd_V02_OCP.brd

J1  SCONN288_DDR506112002KQ  IO  pkg DDR288S_1-1VXC  page 86
  VIN_BULK0  = P12V_MEM_CPU0
  RFU0  = NC
  VIN_MGMT  = P3V3_AUX
  HSCL  = I3C_SPD_DDRA_CPU0_SCL
  HSDA  = I3C_SPD_DDRA_CPU0_SDA
  VSS0  = GND
  DQ0_A  = M_A_CPU0_SA_DQ<0>
  VSS1  = GND
  DQ1_A  = M_A_CPU0_SA_DQ<1>
  VSS2  = GND
  DQS0_A_T  = M_A_CPU0_SA_DQS_DP<0>
  DQS0_A_C  = M_A_CPU0_SA_DQS_DN<0>
  VSS3  = GND
  DQ4_A  = M_A_CPU0_SA_DQ<4>
  VSS4  = GND
  DQ5_A  = M_A_CPU0_SA_DQ<5>
  VSS5  = GND
  DQ8_A  = M_A_CPU0_SA_DQ<8>
  VSS6  = GND
  DQ9_A  = M_A_CPU0_SA_DQ<9>
  VSS7  = GND
  DQS1_A_T  = M_A_CPU0_SA_DQS_DP<1>
  DQS1_A_C  = M_A_CPU0_SA_DQS_DN<1>
  VSS8  = GND
  DQ12_A  = M_A_CPU0_SA_DQ<12>
  VSS9  = GND
  DQ13_A  = M_A_CPU0_SA_DQ<13>
  VSS10  = GND
  DQ16_A  = M_A_CPU0_SA_DQ<16>
  VSS11  = GND
  DQ17_A  = M_A_CPU0_SA_DQ<17>
  VSS12  = GND
  DQS2_A_T  = M_A_CPU0_SA_DQS_DP<2>
  DQS2_A_C  = M_A_CPU0_SA_DQS_DN<2>
  VSS13  = GND
  DQ20_A  = M_A_CPU0_SA_DQ<20>
  VSS14  = GND
  DQ21_A  = M_A_CPU0_SA_DQ<21>
  VSS15  = GND
  DQ24_A  = M_A_CPU0_SA_DQ<24>
  VSS16  = GND
  DQ25_A  = M_A_CPU0_SA_DQ<25>
  VSS17  = GND
  DQS3_A_T  = M_A_CPU0_SA_DQS_DP<3>
  DQS3_A_C  = M_A_CPU0_SA_DQS_DN<3>
  VSS18  = GND
  DQ28_A  = M_A_CPU0_SA_DQ<28>
  VSS19  = GND
  DQ29_A  = M_A_CPU0_SA_DQ<29>
  VSS20  = GND
  CB0_A  = M_A_CPU0_SA_CB<0>
  VSS21  = GND
  CB1_A  = M_A_CPU0_SA_CB<1>
  VSS22  = GND
  DQS4_A_T  = M_A_CPU0_SA_DQS_DP<4>
  DQS4_A_C  = M_A_CPU0_SA_DQS_DN<4>
  VSS23  = GND
  CB4_A  = M_A_CPU0_SA_CB<4>
  VSS24  = GND
  CB5_A  = M_A_CPU0_SA_CB<5>
  VSS25  = GND
  ALERT_N  = M_A_CPU0_ALERT_N
  VSS26  = GND
  CS0_A_N  = M_A_CPU0_SA_CS_N<0>
  VSS27  = GND
  CA0_A  = M_A_CPU0_SA_CA<0>
  VSS28  = GND
  CA2_A  = M_A_CPU0_SA_CA<2>
  VSS29  = GND
  CA4_A  = M_A_CPU0_SA_CA<4>
  VSS30  = GND
  CA6_A  = M_A_CPU0_SA_CA<6>
  VSS31  = GND
  PAR_A  = M_A_CPU0_SA_PAR
  VSS32  = GND
  CA0_B  = M_A_CPU0_SB_CA<0>
  VSS33  = GND
  CA2_B  = M_A_CPU0_SB_CA<2>
  VSS34  = GND
  CA4_B  = M_A_CPU0_SB_CA<4>
  VSS35  = GND
  CA6_B  = M_A_CPU0_SB_CA<6>
  VSS36  = GND
  CS0_B_N  = M_A_CPU0_SB_CS_N<0>
  VSS37  = GND
  \lbd||rsp_a_n\  = M_A_CPU0_SA_RSP<0>
  \lbs||rsp_b_n\  = M_A_CPU0_SB_RSP<0>
  VSS38  = GND
  CB4_B  = M_A_CPU0_SB_CB<4>
  VSS39  = GND
  CB5_B  = M_A_CPU0_SB_CB<5>
  VSS40  = GND
  \dqs9_b_t||tdqs9_b_t||dbi4_b_n\  = M_A_CPU0_SB_DQS_DP<9>
  \dqs9_b_c||tdqs9_b_c\  = M_A_CPU0_SB_DQS_DN<9>
  VSS41  = GND
  CB0_B  = M_A_CPU0_SB_CB<0>
  VSS42  = GND
  CB1_B  = M_A_CPU0_SB_CB<1>
  VSS43  = GND
  DQ0_B  = M_A_CPU0_SB_DQ<0>
  VSS44  = GND
  DQ1_B  = M_A_CPU0_SB_DQ<1>
  VSS45  = GND
  DQS0_B_T  = M_A_CPU0_SB_DQS_DP<0>
  DQS0_B_C  = M_A_CPU0_SB_DQS_DN<0>
  VSS46  = GND
  DQ4_B  = M_A_CPU0_SB_DQ<4>
  VSS47  = GND
  DQ5_B  = M_A_CPU0_SB_DQ<5>
  VSS48  = GND
  DQ8_B  = M_A_CPU0_SB_DQ<8>
  VSS49  = GND
  DQ9_B  = M_A_CPU0_SB_DQ<9>
  VSS50  = GND
  DQS1_B_T  = M_A_CPU0_SB_DQS_DP<1>
  DQS1_B_C  = M_A_CPU0_SB_DQS_DN<1>
  VSS51  = GND
  DQ12_B  = M_A_CPU0_SB_DQ<12>
  VSS52  = GND
  DQ13_B  = M_A_CPU0_SB_DQ<13>
  VSS53  = GND
  DQ16_B  = M_A_CPU0_SB_DQ<16>
  VSS54  = GND
  DQ17_B  = M_A_CPU0_SB_DQ<17>
  VSS55  = GND
  DQS2_B_T  = M_A_CPU0_SB_DQS_DP<2>
  DQS2_B_C  = M_A_CPU0_SB_DQS_DN<2>
  VSS56  = GND
  DQ20_B  = M_A_CPU0_SB_DQ<20>
  VSS57  = GND
  DQ21_B  = M_A_CPU0_SB_DQ<21>
  VSS58  = GND
  DQ24_B  = M_A_CPU0_SB_DQ<24>
  VSS59  = GND
  DQ25_B  = M_A_CPU0_SB_DQ<25>
  VSS60  = GND
  DQS3_B_T  = M_A_CPU0_SB_DQS_DP<3>
  DQS3_B_C  = M_A_CPU0_SB_DQS_DN<3>
  VSS61  = GND
  DQ28_B  = M_A_CPU0_SB_DQ<28>
  VSS62  = GND
  DQ29_B  = M_A_CPU0_SB_DQ<29>
  VSS63  = GND
  RFU1  = NC
  VIN_BULK1  = P12V_MEM_CPU0
  VIN_BULK2  = P12V_MEM_CPU0
  \pwr_good||fail_n\  = PWRGD_CHA_CPU0_DIMM0
  HAS  = PD_CHA_CPU0_DIMM0_SAA
  RFU2  = NC
  RFU3  = NC
  VSS64  = GND
  DQ2_A  = M_A_CPU0_SA_DQ<2>
  VSS65  = GND
  DQ3_A  = M_A_CPU0_SA_DQ<3>
  VSS66  = GND
  \dqs5_a_c||tdqs5_a_c||dqs5_a_t||tdqs5_a_t\  = M_A_CPU0_SA_DQS_DN<5>
  \dqs5_a_t||tdqs5_a_t\  = M_A_CPU0_SA_DQS_DP<5>
  VSS67  = GND
  DQ6_A  = M_A_CPU0_SA_DQ<6>
  VSS68  = GND
  DQ7_A  = M_A_CPU0_SA_DQ<7>
  VSS69  = GND
  DQ10_A  = M_A_CPU0_SA_DQ<10>
  VSS70  = GND
  DQ11_A  = M_A_CPU0_SA_DQ<11>
  VSS71  = GND
  \dqs6_a_c||tdqs6_a_c||dqs6_a_t||tdqs6_a_t\  = M_A_CPU0_SA_DQS_DN<6>
  \dqs6_a_t||tdqs6_a_t\  = M_A_CPU0_SA_DQS_DP<6>
  VSS72  = GND
  DQ14_A  = M_A_CPU0_SA_DQ<14>
  VSS73  = GND
  DQ15_A  = M_A_CPU0_SA_DQ<15>
  VSS74  = GND
  DQ18_A  = M_A_CPU0_SA_DQ<18>
  VSS75  = GND
  DQ19_A  = M_A_CPU0_SA_DQ<19>
  VSS76  = GND
  \dqs7_a_c||tdqs7_a_c\  = M_A_CPU0_SA_DQS_DN<7>
  \dqs7_a_t||tdqs7_a_t\  = M_A_CPU0_SA_DQS_DP<7>
  VSS77  = GND
  DQ22_A  = M_A_CPU0_SA_DQ<22>
  VSS78  = GND
  DQ23_A  = M_A_CPU0_SA_DQ<23>
  VSS79  = GND
  DQ26_A  = M_A_CPU0_SA_DQ<26>
  VSS80  = GND
  DQ27_A  = M_A_CPU0_SA_DQ<27>
  VSS81  = GND
  \dqs8_a_c||tdqs8_a_c\  = M_A_CPU0_SA_DQS_DN<8>
  \dqs8_a_t||tdqs8_a_t\  = M_A_CPU0_SA_DQS_DP<8>
  VSS82  = GND
  DQ30_A  = M_A_CPU0_SA_DQ<30>
  VSS83  = GND
  DQ31_A  = M_A_CPU0_SA_DQ<31>
  VSS84  = GND
  CB2_A  = M_A_CPU0_SA_CB<2>
  VSS85  = GND
  CB3_A  = M_A_CPU0_SA_CB<3>
  VSS86  = GND
  \dqs9_a_c||tdqs9_a_c\  = M_A_CPU0_SA_DQS_DN<9>
  \dqs9_a_t||tdqs9_a_t\  = M_A_CPU0_SA_DQS_DP<9>
  VSS87  = GND
  CB6_A  = M_A_CPU0_SA_CB<6>
  VSS88  = GND
  CB7_A  = M_A_CPU0_SA_CB<7>
  VSS89  = GND
  RESET_N  = M_A_CPU0_RESET_N
  VSS90  = GND
  CS1_A_N  = M_A_CPU0_SA_CS_N<1>
  VSS91  = GND
  CA1_A  = M_A_CPU0_SA_CA<1>
  VSS92  = GND
  CA3_A  = M_A_CPU0_SA_CA<3>
  VSS93  = GND
  CA5_A  = M_A_CPU0_SA_CA<5>
  VSS94  = GND
  CK_T  = M_A_CPU0_CLK_DP<0>
  CK_C  = M_A_CPU0_CLK_DN<0>
  VSS95  = GND
  RFU4  = NC
  CA1_B  = M_A_CPU0_SB_CA<1>
  VSS96  = GND
  CA3_B  = M_A_CPU0_SB_CA<3>
  VSS97  = GND
  CA5_B  = M_A_CPU0_SB_CA<5>
  VSS98  = GND
  PAR_B  = M_A_CPU0_SB_PAR
  VSS99  = GND
  CS1_B_N  = M_A_CPU0_SB_CS_N<1>
  VSS100  = GND
  RFU5  = NC
  RFU6  = NC
  VSS101  = GND
  CB6_B  = M_A_CPU0_SB_CB<6>
  VSS102  = GND
  CB7_B  = M_A_CPU0_SB_CB<7>
  VSS103  = GND
  DQS4_B_C  = M_A_CPU0_SB_DQS_DN<4>
  DQS4_B_T  = M_A_CPU0_SB_DQS_DP<4>
  VSS104  = GND
  CB2_B  = M_A_CPU0_SB_CB<2>
  VSS105  = GND
  CB3_B  = M_A_CPU0_SB_CB<3>
  VSS106  = GND
  DQ2_B  = M_A_CPU0_SB_DQ<2>
  VSS107  = GND
  DQ3_B  = M_A_CPU0_SB_DQ<3>
  VSS108  = GND
  \dqs5_b_c||tdqs5_b_c\  = M_A_CPU0_SB_DQS_DN<5>
  \dqs5_b_t||tdqs5_b_t\  = M_A_CPU0_SB_DQS_DP<5>
  VSS109  = GND
  DQ6_B  = M_A_CPU0_SB_DQ<6>
  VSS110  = GND
  DQ7_B  = M_A_CPU0_SB_DQ<7>
  VSS111  = GND
  DQ10_B  = M_A_CPU0_SB_DQ<10>
  VSS112  = GND
  DQ11_B  = M_A_CPU0_SB_DQ<11>
  VSS113  = GND
  \dqs6_b_c||tdqs6_b_c\  = M_A_CPU0_SB_DQS_DN<6>
  \dqs6_b_t||tdqs6_b_t\  = M_A_CPU0_SB_DQS_DP<6>
  VSS114  = GND
  DQ14_B  = M_A_CPU0_SB_DQ<14>
  VSS115  = GND
  DQ15_B  = M_A_CPU0_SB_DQ<15>
  VSS116  = GND
  DQ18_B  = M_A_CPU0_SB_DQ<18>
  VSS117  = GND
  DQ19_B  = M_A_CPU0_SB_DQ<19>
  VSS118  = GND
  \dqs7_b_c||tdqs7_b_c\  = M_A_CPU0_SB_DQS_DN<7>
  \dqs7_b_t||tdqs7_b_t\  = M_A_CPU0_SB_DQS_DP<7>
  VSS119  = GND
  DQ22_B  = M_A_CPU0_SB_DQ<22>
  VSS120  = GND
  DQ23_B  = M_A_CPU0_SB_DQ<23>
  VSS121  = GND
  DQ26_B  = M_A_CPU0_SB_DQ<26>
  VSS122  = GND
  DQ27_B  = M_A_CPU0_SB_DQ<27>
  VSS123  = GND
  \dqs8_b_c||tdqs8_b_c\  = M_A_CPU0_SB_DQS_DN<8>
  \dqs8_b_t||tdqs8_b_t\  = M_A_CPU0_SB_DQS_DP<8>
  VSS124  = GND
  DQ30_B  = M_A_CPU0_SB_DQ<30>
  VSS125  = GND
  DQ31_B  = M_A_CPU0_SB_DQ<31>
  VSS126  = GND
  G1  = GND
  G2  = GND
  G3  = GND

(kicad_pcb
	(version 20260206)
	(generator "pcbnew")
	(generator_version "10.0")
	(general
		(thickness 1.6)
		(legacy_teardrops no)
	)
	(paper "A4")
	(title_block
		(title "04192023_DAF0TMB3IC0_F0TG_MB_C_brd_V02_OCP.brd")
		(comment 1 "Grand Teton / footprint 2352 of 8354 (J1), pads 93-138 of 291")
	)
	(layers
		(0 "F.Cu" signal "TOP")
		(4 "In1.Cu" signal "GND")
		(6 "In2.Cu" signal "IN1")
		(8 "In3.Cu" signal "GND1")
		(10 "In4.Cu" signal "IN2")
		(12 "In5.Cu" signal "GND2")
		(14 "In6.Cu" signal "IN3")
		(16 "In7.Cu" signal "GND3")
		(18 "In8.Cu" signal "VCC")
		(20 "In9.Cu" signal "VCC1")
		(22 "In10.Cu" signal "GND4")
		(24 "In11.Cu" signal "IN4")
		(26 "In12.Cu" signal "GND5")
		(28 "In13.Cu" signal "IN5")
		(30 "In14.Cu" signal "GND6")
		(32 "In15.Cu" signal "IN6")
		(34 "In16.Cu" signal "GND7")
		(2 "B.Cu" signal "BOTTOM")
		(9 "F.Adhes" user "F.Adhesive")
		(11 "B.Adhes" user "B.Adhesive")
		(13 "F.Paste" user "Package Geometry/Pastemask Top")
		(15 "B.Paste" user "Package Geometry/Pastemask Bottom")
		(5 "F.SilkS" user "Ref Des/Silkscreen Top")
		(7 "B.SilkS" user "Ref Des/Silkscreen Bottom")
		(1 "F.Mask" user "Board Geometry/Soldermask Top")
		(3 "B.Mask" user "Board Geometry/Soldermask Bottom")
		(17 "Dwgs.User" user "User.Drawings")
		(19 "Cmts.User" user "User.Comments")
		(21 "Eco1.User" user "User.Eco1")
		(23 "Eco2.User" user "User.Eco2")
		(25 "Edge.Cuts" user "Board Geometry/Outline")
		(27 "Margin" user)
		(31 "F.CrtYd" user "Package Geometry/Place Bound Top")
		(29 "B.CrtYd" user "Package Geometry/Place Bound Bottom")
		(35 "F.Fab" user "Ref Des/Assembly Top")
		(33 "B.Fab" user "Ref Des/Assembly Bottom")
	)
	(footprint ""
		(layer "F.Cu")
		(at 305.31816 -255.560068 180)
		(property "Reference" "J1"
			(at -2.2098 -81.984088 0)
			(unlocked yes)
			(layer "F.SilkS")
			(effects
				(font
					(size 0.7874 0.5842)
					(thickness 0.1524)
				)
			)
		)
		(property "Value" ""
			(at 0 0 180)
			(layer "F.Fab")
			(effects
				(font
					(size 1.27 1.27)
				)
			)
		)
		(duplicate_pad_numbers_are_jumpers no)
		(pad "93" smd rect
			(at -2.050034 19.975068 90)
			(size 0.519938 1.4986)
			(layers "F.Cu" "F.Mask" "F.Paste")
			(net "M_A_CPU0_SB_DQS_DP<9>")
		)
		(pad "94" smd rect
			(at -2.050034 20.824952 90)
			(size 0.519938 1.4986)
			(layers "F.Cu" "F.Mask" "F.Paste")
			(net "M_A_CPU0_SB_DQS_DN<9>")
		)
		(pad "95" smd rect
			(at -2.050034 21.67509 90)
			(size 0.519938 1.4986)
			(layers "F.Cu" "F.Mask" "F.Paste")
			(net "GND")
		)
		(pad "96" smd rect
			(at -2.050034 22.524974 90)
			(size 0.519938 1.4986)
			(layers "F.Cu" "F.Mask" "F.Paste")
			(net "M_A_CPU0_SB_CB<0>")
		)
		(pad "97" smd rect
			(at -2.050034 23.375112 90)
			(size 0.519938 1.4986)
			(layers "F.Cu" "F.Mask" "F.Paste")
			(net "GND")
		)
		(pad "98" smd rect
			(at -2.050034 24.224996 90)
			(size 0.519938 1.4986)
			(layers "F.Cu" "F.Mask" "F.Paste")
			(net "M_A_CPU0_SB_CB<1>")
		)
		(pad "99" smd rect
			(at -2.050034 25.07488 90)
			(size 0.519938 1.4986)
			(layers "F.Cu" "F.Mask" "F.Paste")
			(net "GND")
		)
		(pad "100" smd rect
			(at -2.050034 25.925018 90)
			(size 0.519938 1.4986)
			(layers "F.Cu" "F.Mask" "F.Paste")
			(net "M_A_CPU0_SB_DQ<0>")
		)
		(pad "101" smd rect
			(at -2.050034 26.774902 90)
			(size 0.519938 1.4986)
			(layers "F.Cu" "F.Mask" "F.Paste")
			(net "GND")
		)
		(pad "102" smd rect
			(at -2.050034 27.62504 90)
			(size 0.519938 1.4986)
			(layers "F.Cu" "F.Mask" "F.Paste")
			(net "M_A_CPU0_SB_DQ<1>")
		)
		(pad "103" smd rect
			(at -2.050034 28.474924 90)
			(size 0.519938 1.4986)
			(layers "F.Cu" "F.Mask" "F.Paste")
			(net "GND")
		)
		(pad "104" smd rect
			(at -2.050034 29.325062 90)
			(size 0.519938 1.4986)
			(layers "F.Cu" "F.Mask" "F.Paste")
			(net "M_A_CPU0_SB_DQS_DP<0>")
		)
		(pad "105" smd rect
			(at -2.050034 30.174946 90)
			(size 0.519938 1.4986)
			(layers "F.Cu" "F.Mask" "F.Paste")
			(net "M_A_CPU0_SB_DQS_DN<0>")
		)
		(pad "106" smd rect
			(at -2.050034 31.025084 90)
			(size 0.519938 1.4986)
			(layers "F.Cu" "F.Mask" "F.Paste")
			(net "GND")
		)
		(pad "107" smd rect
			(at -2.050034 31.874968 90)
			(size 0.519938 1.4986)
			(layers "F.Cu" "F.Mask" "F.Paste")
			(net "M_A_CPU0_SB_DQ<4>")
		)
		(pad "108" smd rect
			(at -2.050034 32.725106 90)
			(size 0.519938 1.4986)
			(layers "F.Cu" "F.Mask" "F.Paste")
			(net "GND")
		)
		(pad "109" smd rect
			(at -2.050034 33.57499 90)
			(size 0.519938 1.4986)
			(layers "F.Cu" "F.Mask" "F.Paste")
			(net "M_A_CPU0_SB_DQ<5>")
		)
		(pad "110" smd rect
			(at -2.050034 34.425128 90)
			(size 0.519938 1.4986)
			(layers "F.Cu" "F.Mask" "F.Paste")
			(net "GND")
		)
		(pad "111" smd rect
			(at -2.050034 35.275012 90)
			(size 0.519938 1.4986)
			(layers "F.Cu" "F.Mask" "F.Paste")
			(net "M_A_CPU0_SB_DQ<8>")
		)
		(pad "112" smd rect
			(at -2.050034 36.124896 90)
			(size 0.519938 1.4986)
			(layers "F.Cu" "F.Mask" "F.Paste")
			(net "GND")
		)
		(pad "113" smd rect
			(at -2.050034 36.975034 90)
			(size 0.519938 1.4986)
			(layers "F.Cu" "F.Mask" "F.Paste")
			(net "M_A_CPU0_SB_DQ<9>")
		)
		(pad "114" smd rect
			(at -2.050034 37.824918 90)
			(size 0.519938 1.4986)
			(layers "F.Cu" "F.Mask" "F.Paste")
			(net "GND")
		)
		(pad "115" smd rect
			(at -2.050034 38.675056 90)
			(size 0.519938 1.4986)
			(layers "F.Cu" "F.Mask" "F.Paste")
			(net "M_A_CPU0_SB_DQS_DP<1>")
		)
		(pad "116" smd rect
			(at -2.050034 39.52494 90)
			(size 0.519938 1.4986)
			(layers "F.Cu" "F.Mask" "F.Paste")
			(net "M_A_CPU0_SB_DQS_DN<1>")
		)
		(pad "117" smd rect
			(at -2.050034 40.375078 90)
			(size 0.519938 1.4986)
			(layers "F.Cu" "F.Mask" "F.Paste")
			(net "GND")
		)
		(pad "118" smd rect
			(at -2.050034 41.224962 90)
			(size 0.519938 1.4986)
			(layers "F.Cu" "F.Mask" "F.Paste")
			(net "M_A_CPU0_SB_DQ<12>")
		)
		(pad "119" smd rect
			(at -2.050034 42.0751 90)
			(size 0.519938 1.4986)
			(layers "F.Cu" "F.Mask" "F.Paste")
			(net "GND")
		)
		(pad "120" smd rect
			(at -2.050034 42.924984 90)
			(size 0.519938 1.4986)
			(layers "F.Cu" "F.Mask" "F.Paste")
			(net "M_A_CPU0_SB_DQ<13>")
		)
		(pad "121" smd rect
			(at -2.050034 43.775122 90)
			(size 0.519938 1.4986)
			(layers "F.Cu" "F.Mask" "F.Paste")
			(net "GND")
		)
		(pad "122" smd rect
			(at -2.050034 44.625006 90)
			(size 0.519938 1.4986)
			(layers "F.Cu" "F.Mask" "F.Paste")
			(net "M_A_CPU0_SB_DQ<16>")
		)
		(pad "123" smd rect
			(at -2.050034 45.47489 90)
			(size 0.519938 1.4986)
			(layers "F.Cu" "F.Mask" "F.Paste")
			(net "GND")
		)
		(pad "124" smd rect
			(at -2.050034 46.325028 90)
			(size 0.519938 1.4986)
			(layers "F.Cu" "F.Mask" "F.Paste")
			(net "M_A_CPU0_SB_DQ<17>")
		)
		(pad "125" smd rect
			(at -2.050034 47.174912 90)
			(size 0.519938 1.4986)
			(layers "F.Cu" "F.Mask" "F.Paste")
			(net "GND")
		)
		(pad "126" smd rect
			(at -2.050034 48.02505 90)
			(size 0.519938 1.4986)
			(layers "F.Cu" "F.Mask" "F.Paste")
			(net "M_A_CPU0_SB_DQS_DP<2>")
		)
		(pad "127" smd rect
			(at -2.050034 48.874934 90)
			(size 0.519938 1.4986)
			(layers "F.Cu" "F.Mask" "F.Paste")
			(net "M_A_CPU0_SB_DQS_DN<2>")
		)
		(pad "128" smd rect
			(at -2.050034 49.725072 90)
			(size 0.519938 1.4986)
			(layers "F.Cu" "F.Mask" "F.Paste")
			(net "GND")
		)
		(pad "129" smd rect
			(at -2.050034 50.574956 90)
			(size 0.519938 1.4986)
			(layers "F.Cu" "F.Mask" "F.Paste")
			(net "M_A_CPU0_SB_DQ<20>")
		)
		(pad "130" smd rect
			(at -2.050034 51.425094 90)
			(size 0.519938 1.4986)
			(layers "F.Cu" "F.Mask" "F.Paste")
			(net "GND")
		)
		(pad "131" smd rect
			(at -2.050034 52.274978 90)
			(size 0.519938 1.4986)
			(layers "F.Cu" "F.Mask" "F.Paste")
			(net "M_A_CPU0_SB_DQ<21>")
		)
		(pad "132" smd rect
			(at -2.050034 53.125116 90)
			(size 0.519938 1.4986)
			(layers "F.Cu" "F.Mask" "F.Paste")
			(net "GND")
		)
		(pad "133" smd rect
			(at -2.050034 53.975 90)
			(size 0.519938 1.4986)
			(layers "F.Cu" "F.Mask" "F.Paste")
			(net "M_A_CPU0_SB_DQ<24>")
		)
		(pad "134" smd rect
			(at -2.050034 54.824884 90)
			(size 0.519938 1.4986)
			(layers "F.Cu" "F.Mask" "F.Paste")
			(net "GND")
		)
		(pad "135" smd rect
			(at -2.050034 55.675022 90)
			(size 0.519938 1.4986)
			(layers "F.Cu" "F.Mask" "F.Paste")
			(net "M_A_CPU0_SB_DQ<25>")
		)
		(pad "136" smd rect
			(at -2.050034 56.524906 90)
			(size 0.519938 1.4986)
			(layers "F.Cu" "F.Mask" "F.Paste")
			(net "GND")
		)
		(pad "137" smd rect
			(at -2.050034 57.375044 90)
			(size 0.519938 1.4986)
			(layers "F.Cu" "F.Mask" "F.Paste")
			(net "M_A_CPU0_SB_DQS_DP<3>")
		)
		(pad "138" smd rect
			(at -2.050034 58.224928 90)
			(size 0.519938 1.4986)
			(layers "F.Cu" "F.Mask" "F.Paste")
			(net "M_A_CPU0_SB_DQS_DN<3>")
		)
	)
)
